# BASEBOARD_FAB2 (Tioga Pass) — schematic netlist excerpt (pin names and nets, part order shuffled) for the footprints in the layout excerpt that follows; sources: Cadence DE-HDL packaged netlist, KiCad conversion of Wiwynn_Tioga_Pass_MB.brd

C1F4  CAP  0.22UF 16V 10% X7R  pkg 0402  page 181 : A = P3E_CPU1_PE3_MP_C_TXN<6> ; B = P3E_CPU1_PE3_MP_TXN<6>
C8B9  CAP_A  22.0UF 4V 20% X6S  pkg 0603V  page 131 : A = P1V05_PCH_STBY ; B = GND
C7C5  CAP  15.0PF 50V 5% COG  pkg 0402LF  page 114 : A = XTAL_PCH_48M_OUT ; B = GND

(kicad_pcb
	(version 20260206)
	(generator "pcbnew")
	(generator_version "10.0")
	(general
		(thickness 1.6)
		(legacy_teardrops no)
	)
	(paper "A4")
	(title_block
		(title "Wiwynn_Tioga_Pass_MB.brd")
		(comment 1 "Tioga Pass / footprints 978-980 of 4770")
	)
	(layers
		(0 "F.Cu" signal "TOP")
		(4 "In1.Cu" signal "L2GND")
		(6 "In2.Cu" signal "L3")
		(8 "In3.Cu" signal "L4GND")
		(10 "In4.Cu" signal "L5")
		(12 "In5.Cu" signal "L6GND")
		(14 "In6.Cu" signal "L7VCC")
		(16 "In7.Cu" signal "L8VCC")
		(18 "In8.Cu" signal "L9GND")
		(20 "In9.Cu" signal "L10")
		(22 "In10.Cu" signal "L11GND")
		(24 "In11.Cu" signal "L12")
		(26 "In12.Cu" signal "L13GND")
		(2 "B.Cu" signal "BOTTOM")
		(9 "F.Adhes" user "F.Adhesive")
		(11 "B.Adhes" user "B.Adhesive")
		(13 "F.Paste" user "Package Geometry/Pastemask Top")
		(15 "B.Paste" user "Package Geometry/Pastemask Bottom")
		(5 "F.SilkS" user "Ref Des/Silkscreen Top")
		(7 "B.SilkS" user "Ref Des/Silkscreen Bottom")
		(1 "F.Mask" user "Board Geometry/Soldermask Top")
		(3 "B.Mask" user "Board Geometry/Soldermask Bottom")
		(17 "Dwgs.User" user "User.Drawings")
		(19 "Cmts.User" user "User.Comments")
		(21 "Eco1.User" user "User.Eco1")
		(23 "Eco2.User" user "User.Eco2")
		(25 "Edge.Cuts" user "Board Geometry/Outline")
		(27 "Margin" user)
		(31 "F.CrtYd" user "Package Geometry/Place Bound Top")
		(29 "B.CrtYd" user "Package Geometry/Place Bound Bottom")
		(35 "F.Fab" user "Ref Des/Assembly Top")
		(33 "B.Fab" user "Ref Des/Assembly Bottom")
	)
	(footprint ""
		(layer "F.Cu")
		(at 13.8938 -34.798 90)
		(property "Reference" "C1F4"
			(at 0 0 90)
			(layer "F.SilkS")
			(hide yes)
			(effects
				(font
					(size 1.27 1.27)
				)
			)
		)
		(property "Value" ""
			(at 0 0 90)
			(layer "F.Fab")
			(effects
				(font
					(size 1.27 1.27)
				)
			)
		)
		(duplicate_pad_numbers_are_jumpers no)
		(fp_rect
			(start -0.3048 -0.1016)
			(end 0.3048 0.9906)
			(stroke
				(width 0)
				(type default)
			)
			(fill no)
			(layer "F.CrtYd")
		)
		(fp_line
			(start 0.3048 -0.1016)
			(end -0.3048 -0.1016)
			(stroke
				(width 0.1)
				(type default)
			)
			(layer "F.Fab")
		)
		(fp_line
			(start -0.3048 -0.1016)
			(end -0.3048 0.9906)
			(stroke
				(width 0.1)
				(type default)
			)
			(layer "F.Fab")
		)
		(fp_line
			(start 0.3048 0.9906)
			(end 0.3048 -0.1016)
			(stroke
				(width 0.1)
				(type default)
			)
			(layer "F.Fab")
		)
		(fp_line
			(start -0.3048 0.9906)
			(end 0.3048 0.9906)
			(stroke
				(width 0.1)
				(type default)
			)
			(layer "F.Fab")
		)
		(pad "1" smd rect
			(at 0 0 90)
			(size 0.508 0.508)
			(layers "F.Cu" "F.Mask" "F.Paste")
			(net "P3E_CPU1_PE3_MP_C_TXN<6>")
		)
		(pad "2" smd rect
			(at 0 0.889 90)
			(size 0.508 0.508)
			(layers "F.Cu" "F.Mask" "F.Paste")
			(net "P3E_CPU1_PE3_MP_TXN<6>")
		)
		(zone
			(layer "F.Cu")
			(hatch none 0.5)
			(connect_pads
				(clearance 0)
			)
			(min_thickness 0.25)
			(keepout
				(tracks not_allowed)
				(vias allowed)
				(pads allowed)
				(copperpour not_allowed)
				(footprints allowed)
			)
			(placement
				(enabled no)
				(sheetname "")
			)
			(fill
				(thermal_gap 0.5)
				(thermal_bridge_width 0.5)
				(island_removal_mode 0)
			)
			(polygon
				(pts
					(xy 14.1478 -34.544) (xy 14.5288 -34.544) (xy 14.5288 -35.052) (xy 14.1478 -35.052)
				)
			)
		)
		(zone
			(layer "F.Cu")
			(hatch none 0.5)
			(connect_pads
				(clearance 0)
			)
			(min_thickness 0.25)
			(keepout
				(tracks allowed)
				(vias not_allowed)
				(pads allowed)
				(copperpour not_allowed)
				(footprints allowed)
			)
			(placement
				(enabled no)
				(sheetname "")
			)
			(fill
				(thermal_gap 0.5)
				(thermal_bridge_width 0.5)
				(island_removal_mode 0)
			)
			(polygon
				(pts
					(xy 14.1478 -34.544) (xy 14.5288 -34.544) (xy 14.5288 -35.052) (xy 14.1478 -35.052)
				)
			)
		)
	)
	(footprint ""
		(layer "F.Cu")
		(at 368.69624 -107.106466)
		(property "Reference" "C7C5"
			(at 0 0 0)
			(layer "F.SilkS")
			(hide yes)
			(effects
				(font
					(size 1.27 1.27)
				)
			)
		)
		(property "Value" ""
			(at 0 0 0)
			(layer "F.Fab")
			(effects
				(font
					(size 1.27 1.27)
				)
			)
		)
		(duplicate_pad_numbers_are_jumpers no)
		(fp_poly
			(pts
				(xy 0.3048 -0.1016) (xy 0.3048 0.9906) (xy -0.3048 0.9906) (xy -0.3048 -0.1016)
			)
			(stroke
				(width 0)
				(type default)
			)
			(fill no)
			(layer "F.CrtYd")
		)
		(fp_line
			(start -0.3048 -0.1016)
			(end -0.3048 0.9906)
			(stroke
				(width 0.1)
				(type default)
			)
			(layer "F.Fab")
		)
		(fp_line
			(start -0.3048 0.9906)
			(end 0.3048 0.9906)
			(stroke
				(width 0.1)
				(type default)
			)
			(layer "F.Fab")
		)
		(fp_line
			(start 0.3048 -0.1016)
			(end -0.3048 -0.1016)
			(stroke
				(width 0.1)
				(type default)
			)
			(layer "F.Fab")
		)
		(fp_line
			(start 0.3048 0.9906)
			(end 0.3048 -0.1016)
			(stroke
				(width 0.1)
				(type default)
			)
			(layer "F.Fab")
		)
		(pad "1" smd rect
			(at 0 0)
			(size 0.508 0.508)
			(layers "F.Cu" "F.Mask" "F.Paste")
			(net "XTAL_PCH_48M_OUT")
		)
		(pad "2" smd rect
			(at 0 0.889)
			(size 0.508 0.508)
			(layers "F.Cu" "F.Mask" "F.Paste")
			(net "GND")
		)
		(zone
			(layer "F.Cu")
			(hatch none 0.5)
			(connect_pads
				(clearance 0)
			)
			(min_thickness 0.25)
			(keepout
				(tracks allowed)
				(vias not_allowed)
				(pads allowed)
				(copperpour not_allowed)
				(footprints allowed)
			)
			(placement
				(enabled no)
				(sheetname "")
			)
			(fill
				(thermal_gap 0.5)
				(thermal_bridge_width 0.5)
				(island_removal_mode 0)
			)
			(polygon
				(pts
					(xy 368.44224 -106.852466) (xy 368.95024 -106.852466) (xy 368.95024 -106.471466) (xy 368.44224 -106.471466)
				)
			)
		)
		(zone
			(layer "F.Cu")
			(hatch none 0.5)
			(connect_pads
				(clearance 0)
			)
			(min_thickness 0.25)
			(keepout
				(tracks not_allowed)
				(vias allowed)
				(pads allowed)
				(copperpour not_allowed)
				(footprints allowed)
			)
			(placement
				(enabled no)
				(sheetname "")
			)
			(fill
				(thermal_gap 0.5)
				(thermal_bridge_width 0.5)
				(island_removal_mode 0)
			)
			(polygon
				(pts
					(xy 368.44224 -106.471466) (xy 368.95024 -106.471466) (xy 368.95024 -106.852466) (xy 368.44224 -106.852466)
				)
			)
		)
	)
	(footprint ""
		(layer "F.Cu")
		(at 408.178 -126.238)
		(property "Reference" "C8B9"
			(at 0 0 0)
			(layer "F.SilkS")
			(hide yes)
			(effects
				(font
					(size 1.27 1.27)
				)
			)
		)
		(property "Value" ""
			(at 0 0 0)
			(layer "F.Fab")
			(effects
				(font
					(size 1.27 1.27)
				)
			)
		)
		(duplicate_pad_numbers_are_jumpers no)
		(fp_poly
			(pts
				(xy -0.4953 -0.2032) (xy 0.4953 -0.2032) (xy 0.4953 1.6002) (xy -0.4953 1.6002)
			)
			(stroke
				(width 0)
				(type default)
			)
			(fill no)
			(layer "F.CrtYd")
		)
		(fp_line
			(start -0.4953 -0.2032)
			(end 0.4953 -0.2032)
			(stroke
				(width 0.1)
				(type default)
			)
			(layer "F.Fab")
		)
		(fp_line
			(start -0.4953 1.6002)
			(end -0.4953 -0.2032)
			(stroke
				(width 0.1)
				(type default)
			)
			(layer "F.Fab")
		)
		(fp_line
			(start 0.4953 -0.2032)
			(end 0.4953 1.6002)
			(stroke
				(width 0.1)
				(type default)
			)
			(layer "F.Fab")
		)
		(fp_line
			(start 0.4953 1.6002)
			(end -0.4953 1.6002)
			(stroke
				(width 0.1)
				(type default)
			)
			(layer "F.Fab")
		)
		(pad "1" smd rect
			(at 0 0)
			(size 0.762 0.889)
			(layers "F.Cu" "F.Mask" "F.Paste")
			(net "P1V05_PCH_STBY")
		)
		(pad "2" smd rect
			(at 0 1.397)
			(size 0.762 0.889)
			(layers "F.Cu" "F.Mask" "F.Paste")
			(net "GND")
		)
		(zone
			(layer "F.Cu")
			(hatch none 0.5)
			(connect_pads
				(clearance 0)
			)
			(min_thickness 0.25)
			(keepout
				(tracks not_allowed)
				(vias allowed)
				(pads allowed)
				(copperpour not_allowed)
				(footprints allowed)
			)
			(placement
				(enabled no)
				(sheetname "")
			)
			(fill
				(thermal_gap 0.5)
				(thermal_bridge_width 0.5)
				(island_removal_mode 0)
			)
			(polygon
				(pts
					(xy 407.797 -125.7935) (xy 408.559 -125.7935) (xy 408.559 -125.2855) (xy 407.797 -125.2855)
				)
			)
		)
	)
)
